# T6G (Grand Teton) — schematic netlist excerpt (pin names and nets, part order shuffled) for the footprints in the layout excerpt that follows; sources: Cadence DE-HDL packaged netlist, KiCad conversion of 04192023_DAF0TMB3IC0_F0TG_MB_C_brd_V02_OCP.brd

C6049  Q_CAP  0.01UF 50V 10% X7R  pkg C0402  page 177 : A = P3V3_AUX ; B = GND
C537  Q_CAP  10UF 25V 10% X6S  pkg C0805  page 107 : A = P12V_MEM_CPU1 ; B = GND
C530  Q_CAP  10UF 25V 10% X6S  pkg C0805  page 104 : A = P12V_MEM_CPU1 ; B = GND

(kicad_pcb
	(version 20260206)
	(generator "pcbnew")
	(generator_version "10.0")
	(general
		(thickness 1.6)
		(legacy_teardrops no)
	)
	(paper "A4")
	(title_block
		(title "04192023_DAF0TMB3IC0_F0TG_MB_C_brd_V02_OCP.brd")
		(comment 1 "Grand Teton / footprints 7469-7471 of 8354")
	)
	(layers
		(0 "F.Cu" signal "TOP")
		(4 "In1.Cu" signal "GND")
		(6 "In2.Cu" signal "IN1")
		(8 "In3.Cu" signal "GND1")
		(10 "In4.Cu" signal "IN2")
		(12 "In5.Cu" signal "GND2")
		(14 "In6.Cu" signal "IN3")
		(16 "In7.Cu" signal "GND3")
		(18 "In8.Cu" signal "VCC")
		(20 "In9.Cu" signal "VCC1")
		(22 "In10.Cu" signal "GND4")
		(24 "In11.Cu" signal "IN4")
		(26 "In12.Cu" signal "GND5")
		(28 "In13.Cu" signal "IN5")
		(30 "In14.Cu" signal "GND6")
		(32 "In15.Cu" signal "IN6")
		(34 "In16.Cu" signal "GND7")
		(2 "B.Cu" signal "BOTTOM")
		(9 "F.Adhes" user "F.Adhesive")
		(11 "B.Adhes" user "B.Adhesive")
		(13 "F.Paste" user "Package Geometry/Pastemask Top")
		(15 "B.Paste" user "Package Geometry/Pastemask Bottom")
		(5 "F.SilkS" user "Ref Des/Silkscreen Top")
		(7 "B.SilkS" user "Ref Des/Silkscreen Bottom")
		(1 "F.Mask" user "Board Geometry/Soldermask Top")
		(3 "B.Mask" user "Board Geometry/Soldermask Bottom")
		(17 "Dwgs.User" user "User.Drawings")
		(19 "Cmts.User" user "User.Comments")
		(21 "Eco1.User" user "User.Eco1")
		(23 "Eco2.User" user "User.Eco2")
		(25 "Edge.Cuts" user "Board Geometry/Outline")
		(27 "Margin" user)
		(31 "F.CrtYd" user "Package Geometry/Place Bound Top")
		(29 "B.CrtYd" user "Package Geometry/Place Bound Bottom")
		(35 "F.Fab" user "Ref Des/Assembly Top")
		(33 "B.Fab" user "Ref Des/Assembly Bottom")
	)
	(footprint ""
		(layer "B.Cu")
		(at 168.528238 -192.66027)
		(property "Reference" "C530"
			(at 0 0 0)
			(layer "B.SilkS")
			(hide yes)
			(effects
				(font
					(size 1.27 1.27)
				)
				(justify mirror)
			)
		)
		(property "Value" ""
			(at 0 0 0)
			(layer "B.Fab")
			(effects
				(font
					(size 1.27 1.27)
				)
				(justify mirror)
			)
		)
		(duplicate_pad_numbers_are_jumpers no)
		(fp_line
			(start -1.524 -0.762)
			(end -1.524 0.762)
			(stroke
				(width 0.1524)
				(type default)
			)
			(layer "B.SilkS")
		)
		(fp_line
			(start -1.524 0.762)
			(end 1.524 0.762)
			(stroke
				(width 0.1524)
				(type default)
			)
			(layer "B.SilkS")
		)
		(fp_line
			(start 1.524 -0.762)
			(end -1.524 -0.762)
			(stroke
				(width 0.1524)
				(type default)
			)
			(layer "B.SilkS")
		)
		(fp_line
			(start 1.524 0.762)
			(end 1.524 -0.762)
			(stroke
				(width 0.1524)
				(type default)
			)
			(layer "B.SilkS")
		)
		(fp_line
			(start -1.1049 -0.724916)
			(end 1.1049 -0.724916)
			(stroke
				(width 0.1)
				(type default)
			)
			(layer "B.Fab")
		)
		(fp_line
			(start -1.1049 0.724916)
			(end -1.1049 -0.724916)
			(stroke
				(width 0.1)
				(type default)
			)
			(layer "B.Fab")
		)
		(fp_line
			(start 1.1049 -0.724916)
			(end 1.1049 0.724916)
			(stroke
				(width 0.1)
				(type default)
			)
			(layer "B.Fab")
		)
		(fp_line
			(start 1.1049 0.724916)
			(end -1.1049 0.724916)
			(stroke
				(width 0.1)
				(type default)
			)
			(layer "B.Fab")
		)
		(pad "1" smd rect
			(at 0.889 0)
			(size 1.016 1.27)
			(layers "B.Cu" "B.Mask" "B.Paste")
			(net "P12V_MEM_CPU1")
		)
		(pad "2" smd rect
			(at -0.889 0)
			(size 1.016 1.27)
			(layers "B.Cu" "B.Mask" "B.Paste")
			(net "GND")
		)
	)
	(footprint ""
		(layer "B.Cu")
		(at 187.060078 -192.66027 180)
		(property "Reference" "C537"
			(at 0 0 0)
			(layer "B.SilkS")
			(hide yes)
			(effects
				(font
					(size 1.27 1.27)
				)
				(justify mirror)
			)
		)
		(property "Value" ""
			(at 0 0 0)
			(layer "B.Fab")
			(effects
				(font
					(size 1.27 1.27)
				)
				(justify mirror)
			)
		)
		(duplicate_pad_numbers_are_jumpers no)
		(fp_line
			(start 1.524 0.762)
			(end 1.524 -0.762)
			(stroke
				(width 0.1524)
				(type default)
			)
			(layer "B.SilkS")
		)
		(fp_line
			(start 1.524 -0.762)
			(end -1.524 -0.762)
			(stroke
				(width 0.1524)
				(type default)
			)
			(layer "B.SilkS")
		)
		(fp_line
			(start -1.524 0.762)
			(end 1.524 0.762)
			(stroke
				(width 0.1524)
				(type default)
			)
			(layer "B.SilkS")
		)
		(fp_line
			(start -1.524 -0.762)
			(end -1.524 0.762)
			(stroke
				(width 0.1524)
				(type default)
			)
			(layer "B.SilkS")
		)
		(fp_line
			(start 1.1049 0.724916)
			(end -1.1049 0.724916)
			(stroke
				(width 0.1)
				(type default)
			)
			(layer "B.Fab")
		)
		(fp_line
			(start 1.1049 -0.724916)
			(end 1.1049 0.724916)
			(stroke
				(width 0.1)
				(type default)
			)
			(layer "B.Fab")
		)
		(fp_line
			(start -1.1049 0.724916)
			(end -1.1049 -0.724916)
			(stroke
				(width 0.1)
				(type default)
			)
			(layer "B.Fab")
		)
		(fp_line
			(start -1.1049 -0.724916)
			(end 1.1049 -0.724916)
			(stroke
				(width 0.1)
				(type default)
			)
			(layer "B.Fab")
		)
		(pad "1" smd rect
			(at 0.889 0 180)
			(size 1.016 1.27)
			(layers "B.Cu" "B.Mask" "B.Paste")
			(net "P12V_MEM_CPU1")
		)
		(pad "2" smd rect
			(at -0.889 0 180)
			(size 1.016 1.27)
			(layers "B.Cu" "B.Mask" "B.Paste")
			(net "GND")
		)
	)
	(footprint ""
		(layer "B.Cu")
		(at 132.865114 -33.199578 -90)
		(property "Reference" "C6049"
			(at 0 0 90)
			(layer "B.SilkS")
			(hide yes)
			(effects
				(font
					(size 1.27 1.27)
				)
				(justify mirror)
			)
		)
		(property "Value" ""
			(at 0 0 90)
			(layer "B.Fab")
			(effects
				(font
					(size 1.27 1.27)
				)
				(justify mirror)
			)
		)
		(duplicate_pad_numbers_are_jumpers no)
		(fp_line
			(start -0.7874 0.4064)
			(end 0.7874 0.4064)
			(stroke
				(width 0.1524)
				(type default)
			)
			(layer "B.SilkS")
		)
		(fp_line
			(start 0.7874 0.4064)
			(end 0.7874 -0.4064)
			(stroke
				(width 0.1524)
				(type default)
			)
			(layer "B.SilkS")
		)
		(fp_line
			(start -0.7874 -0.4064)
			(end -0.7874 0.4064)
			(stroke
				(width 0.1524)
				(type default)
			)
			(layer "B.SilkS")
		)
		(fp_line
			(start 0.7874 -0.4064)
			(end -0.7874 -0.4064)
			(stroke
				(width 0.1524)
				(type default)
			)
			(layer "B.SilkS")
		)
		(fp_line
			(start -0.67945 0.3048)
			(end -0.120396 0.3048)
			(stroke
				(width 0.1)
				(type default)
			)
			(layer "B.Fab")
		)
		(fp_line
			(start -0.120396 0.3048)
			(end -0.120396 0.2794)
			(stroke
				(width 0.1)
				(type default)
			)
			(layer "B.Fab")
		)
		(fp_line
			(start 0.12065 0.3048)
			(end 0.67945 0.3048)
			(stroke
				(width 0.1)
				(type default)
			)
			(layer "B.Fab")
		)
		(fp_line
			(start 0.67945 0.3048)
			(end 0.67945 -0.305054)
			(stroke
				(width 0.1)
				(type default)
			)
			(layer "B.Fab")
		)
		(fp_line
			(start -0.120396 0.2794)
			(end 0.12065 0.2794)
			(stroke
				(width 0.1)
				(type default)
			)
			(layer "B.Fab")
		)
		(fp_line
			(start 0.12065 0.2794)
			(end 0.12065 0.3048)
			(stroke
				(width 0.1)
				(type default)
			)
			(layer "B.Fab")
		)
		(fp_line
			(start -0.12065 -0.2794)
			(end -0.12065 -0.3048)
			(stroke
				(width 0.1)
				(type default)
			)
			(layer "B.Fab")
		)
		(fp_line
			(start 0.12065 -0.2794)
			(end -0.12065 -0.2794)
			(stroke
				(width 0.1)
				(type default)
			)
			(layer "B.Fab")
		)
		(fp_line
			(start -0.67945 -0.3048)
			(end -0.67945 0.3048)
			(stroke
				(width 0.1)
				(type default)
			)
			(layer "B.Fab")
		)
		(fp_line
			(start -0.12065 -0.3048)
			(end -0.67945 -0.3048)
			(stroke
				(width 0.1)
				(type default)
			)
			(layer "B.Fab")
		)
		(fp_line
			(start 0.12065 -0.305054)
			(end 0.12065 -0.2794)
			(stroke
				(width 0.1)
				(type default)
			)
			(layer "B.Fab")
		)
		(fp_line
			(start 0.67945 -0.305054)
			(end 0.12065 -0.305054)
			(stroke
				(width 0.1)
				(type default)
			)
			(layer "B.Fab")
		)
		(pad "1" smd circle
			(at 0.40005 0 90)
			(size 0 0)
			(layers "B.Cu" "B.Mask" "B.Paste")
			(net "P3V3_AUX")
		)
		(pad "2" smd circle
			(at -0.40005 0 90)
			(size 0 0)
			(layers "B.Cu" "B.Mask" "B.Paste")
			(net "GND")
		)
	)
)
